(kicad_pcb
	(version 20260206)
	(generator "pcbnew")
	(generator_version "10.0")
	(general
		(thickness 1.6)
		(legacy_teardrops no)
	)
	(paper "A4")
	(title_block
		(title "01162023_DA0F0TEBIF0_F0T_Expander_BD_F_brd_V02_OCP.brd")
		(comment 1 "Grand Teton / footprints 6564-6571 of 9728")
	)
	(layers
		(0 "F.Cu" signal "TOP")
		(4 "In1.Cu" signal "GND")
		(6 "In2.Cu" signal "VCC")
		(8 "In3.Cu" signal "VCC1")
		(10 "In4.Cu" signal "GND1")
		(12 "In5.Cu" signal "IN1")
		(14 "In6.Cu" signal "GND2")
		(16 "In7.Cu" signal "IN2")
		(18 "In8.Cu" signal "GND3")
		(20 "In9.Cu" signal "IN3")
		(22 "In10.Cu" signal "GND4")
		(24 "In11.Cu" signal "IN4")
		(26 "In12.Cu" signal "GND5")
		(28 "In13.Cu" signal "IN5")
		(30 "In14.Cu" signal "GND6")
		(32 "In15.Cu" signal "IN6")
		(34 "In16.Cu" signal "GND7")
		(2 "B.Cu" signal "BOTTOM")
		(9 "F.Adhes" user "F.Adhesive")
		(11 "B.Adhes" user "B.Adhesive")
		(13 "F.Paste" user "Package Geometry/Pastemask Top")
		(15 "B.Paste" user "Package Geometry/Pastemask Bottom")
		(5 "F.SilkS" user "Ref Des/Silkscreen Top")
		(7 "B.SilkS" user "Ref Des/Silkscreen Bottom")
		(1 "F.Mask" user "Board Geometry/Soldermask Top")
		(3 "B.Mask" user "Board Geometry/Soldermask Bottom")
		(17 "Dwgs.User" user "User.Drawings")
		(19 "Cmts.User" user "User.Comments")
		(21 "Eco1.User" user "User.Eco1")
		(23 "Eco2.User" user "User.Eco2")
		(25 "Edge.Cuts" user "Board Geometry/Outline")
		(27 "Margin" user)
		(31 "F.CrtYd" user "Package Geometry/Place Bound Top")
		(29 "B.CrtYd" user "Package Geometry/Place Bound Bottom")
		(35 "F.Fab" user "Ref Des/Assembly Top")
		(33 "B.Fab" user "Ref Des/Assembly Bottom")
	)
	(footprint ""
		(layer "F.Cu")
		(at 407.696162 -387.942836 180)
		(property "Reference" "R1856"
			(at 0 0 180)
			(layer "F.SilkS")
			(hide yes)
			(effects
				(font
					(size 1.27 1.27)
				)
			)
		)
		(property "Value" ""
			(at 0 0 180)
			(layer "F.Fab")
			(effects
				(font
					(size 1.27 1.27)
				)
			)
		)
		(duplicate_pad_numbers_are_jumpers no)
		(fp_line
			(start 0.7874 0.4064)
			(end -0.7874 0.4064)
			(stroke
				(width 0.1524)
				(type default)
			)
			(layer "F.SilkS")
		)
		(fp_line
			(start 0.7874 -0.4064)
			(end 0.7874 0.4064)
			(stroke
				(width 0.1524)
				(type default)
			)
			(layer "F.SilkS")
		)
		(fp_line
			(start -0.7874 0.4064)
			(end -0.7874 -0.4064)
			(stroke
				(width 0.1524)
				(type default)
			)
			(layer "F.SilkS")
		)
		(fp_line
			(start -0.7874 -0.4064)
			(end 0.7874 -0.4064)
			(stroke
				(width 0.1524)
				(type default)
			)
			(layer "F.SilkS")
		)
		(fp_line
			(start 0.67945 0.3048)
			(end 0.120396 0.3048)
			(stroke
				(width 0.1)
				(type default)
			)
			(layer "F.Fab")
		)
		(fp_line
			(start 0.67945 -0.3048)
			(end 0.67945 0.3048)
			(stroke
				(width 0.1)
				(type default)
			)
			(layer "F.Fab")
		)
		(fp_line
			(start 0.12065 -0.2794)
			(end 0.12065 -0.3048)
			(stroke
				(width 0.1)
				(type default)
			)
			(layer "F.Fab")
		)
		(fp_line
			(start 0.12065 -0.3048)
			(end 0.67945 -0.3048)
			(stroke
				(width 0.1)
				(type default)
			)
			(layer "F.Fab")
		)
		(fp_line
			(start 0.120396 0.3048)
			(end 0.120396 0.2794)
			(stroke
				(width 0.1)
				(type default)
			)
			(layer "F.Fab")
		)
		(fp_line
			(start 0.120396 0.2794)
			(end -0.12065 0.2794)
			(stroke
				(width 0.1)
				(type default)
			)
			(layer "F.Fab")
		)
		(fp_line
			(start -0.12065 0.3048)
			(end -0.67945 0.3048)
			(stroke
				(width 0.1)
				(type default)
			)
			(layer "F.Fab")
		)
		(fp_line
			(start -0.12065 0.2794)
			(end -0.12065 0.3048)
			(stroke
				(width 0.1)
				(type default)
			)
			(layer "F.Fab")
		)
		(fp_line
			(start -0.12065 -0.2794)
			(end 0.12065 -0.2794)
			(stroke
				(width 0.1)
				(type default)
			)
			(layer "F.Fab")
		)
		(fp_line
			(start -0.12065 -0.305054)
			(end -0.12065 -0.2794)
			(stroke
				(width 0.1)
				(type default)
			)
			(layer "F.Fab")
		)
		(fp_line
			(start -0.67945 0.3048)
			(end -0.67945 -0.305054)
			(stroke
				(width 0.1)
				(type default)
			)
			(layer "F.Fab")
		)
		(fp_line
			(start -0.67945 -0.305054)
			(end -0.12065 -0.305054)
			(stroke
				(width 0.1)
				(type default)
			)
			(layer "F.Fab")
		)
		(pad "1" smd circle
			(at -0.40005 0 180)
			(size 0 0)
			(layers "F.Cu" "F.Mask" "F.Paste")
			(net "GPU_WP_HW_CTRL_R_N")
		)
		(pad "2" smd circle
			(at 0.40005 0 180)
			(size 0 0)
			(layers "F.Cu" "F.Mask" "F.Paste")
			(net "GPU_WP_HW_CTRL_N")
		)
	)
	(footprint ""
		(layer "F.Cu")
		(at 463.658458 -534.632662 180)
		(property "Reference" "SCREW_SSD10_2"
			(at -5.6007 -1.402334 0)
			(unlocked yes)
			(layer "B.SilkS")
			(effects
				(font
					(size 0.7874 0.5842)
					(thickness 0.1524)
				)
				(justify mirror)
			)
		)
		(property "Value" ""
			(at 0 0 180)
			(layer "F.Fab")
			(effects
				(font
					(size 1.27 1.27)
				)
			)
		)
		(duplicate_pad_numbers_are_jumpers no)
		(pad "1" thru_hole circle
			(at 0 0 180)
			(size 0.4572 0.4572)
			(drill 0.2032)
			(layers "*.Cu" "*.Mask")
			(remove_unused_layers no)
			(net "Net_9153")
			(clearance 0.127)
			(thermal_gap 0.127)
			(padstack
				(mode front_inner_back)
				(layer "Inner"
					(shape circle)
					(size 0.4572 0.4572)
					(clearance 0.127)
				)
				(layer "B.Cu"
					(shape circle)
					(size 0.508 0.508)
					(clearance 0.1016)
				)
			)
		)
	)
	(footprint ""
		(layer "F.Cu")
		(at 38.599872 -152.295352 180)
		(property "Reference" "R17"
			(at 0 0 180)
			(layer "F.SilkS")
			(hide yes)
			(effects
				(font
					(size 1.27 1.27)
				)
			)
		)
		(property "Value" ""
			(at 0 0 180)
			(layer "F.Fab")
			(effects
				(font
					(size 1.27 1.27)
				)
			)
		)
		(duplicate_pad_numbers_are_jumpers no)
		(fp_line
			(start 0.7874 0.4064)
			(end -0.7874 0.4064)
			(stroke
				(width 0.1524)
				(type default)
			)
			(layer "F.SilkS")
		)
		(fp_line
			(start 0.7874 -0.4064)
			(end 0.7874 0.4064)
			(stroke
				(width 0.1524)
				(type default)
			)
			(layer "F.SilkS")
		)
		(fp_line
			(start -0.7874 0.4064)
			(end -0.7874 -0.4064)
			(stroke
				(width 0.1524)
				(type default)
			)
			(layer "F.SilkS")
		)
		(fp_line
			(start -0.7874 -0.4064)
			(end 0.7874 -0.4064)
			(stroke
				(width 0.1524)
				(type default)
			)
			(layer "F.SilkS")
		)
		(fp_line
			(start 0.67945 0.3048)
			(end 0.120396 0.3048)
			(stroke
				(width 0.1)
				(type default)
			)
			(layer "F.Fab")
		)
		(fp_line
			(start 0.67945 -0.3048)
			(end 0.67945 0.3048)
			(stroke
				(width 0.1)
				(type default)
			)
			(layer "F.Fab")
		)
		(fp_line
			(start 0.12065 -0.2794)
			(end 0.12065 -0.3048)
			(stroke
				(width 0.1)
				(type default)
			)
			(layer "F.Fab")
		)
		(fp_line
			(start 0.12065 -0.3048)
			(end 0.67945 -0.3048)
			(stroke
				(width 0.1)
				(type default)
			)
			(layer "F.Fab")
		)
		(fp_line
			(start 0.120396 0.3048)
			(end 0.120396 0.2794)
			(stroke
				(width 0.1)
				(type default)
			)
			(layer "F.Fab")
		)
		(fp_line
			(start 0.120396 0.2794)
			(end -0.12065 0.2794)
			(stroke
				(width 0.1)
				(type default)
			)
			(layer "F.Fab")
		)
		(fp_line
			(start -0.12065 0.3048)
			(end -0.67945 0.3048)
			(stroke
				(width 0.1)
				(type default)
			)
			(layer "F.Fab")
		)
		(fp_line
			(start -0.12065 0.2794)
			(end -0.12065 0.3048)
			(stroke
				(width 0.1)
				(type default)
			)
			(layer "F.Fab")
		)
		(fp_line
			(start -0.12065 -0.2794)
			(end 0.12065 -0.2794)
			(stroke
				(width 0.1)
				(type default)
			)
			(layer "F.Fab")
		)
		(fp_line
			(start -0.12065 -0.305054)
			(end -0.12065 -0.2794)
			(stroke
				(width 0.1)
				(type default)
			)
			(layer "F.Fab")
		)
		(fp_line
			(start -0.67945 0.3048)
			(end -0.67945 -0.305054)
			(stroke
				(width 0.1)
				(type default)
			)
			(layer "F.Fab")
		)
		(fp_line
			(start -0.67945 -0.305054)
			(end -0.12065 -0.305054)
			(stroke
				(width 0.1)
				(type default)
			)
			(layer "F.Fab")
		)
		(pad "1" smd circle
			(at -0.40005 0 180)
			(size 0 0)
			(layers "F.Cu" "F.Mask" "F.Paste")
			(net "NCSI_NIC0_RXD1")
		)
		(pad "2" smd circle
			(at 0.40005 0 180)
			(size 0 0)
			(layers "F.Cu" "F.Mask" "F.Paste")
			(net "GND")
		)
	)
	(footprint ""
		(layer "F.Cu")
		(at 36.638484 -119.198898)
		(property "Reference" "C47"
			(at 0 0 0)
			(layer "F.SilkS")
			(hide yes)
			(effects
				(font
					(size 1.27 1.27)
				)
			)
		)
		(property "Value" ""
			(at 0 0 0)
			(layer "F.Fab")
			(effects
				(font
					(size 1.27 1.27)
				)
			)
		)
		(duplicate_pad_numbers_are_jumpers no)
		(fp_line
			(start -0.299974 -0.150114)
			(end 0.299974 -0.150114)
			(stroke
				(width 0.1)
				(type default)
			)
			(layer "F.Fab")
		)
		(fp_line
			(start -0.299974 0.150114)
			(end -0.299974 -0.150114)
			(stroke
				(width 0.1)
				(type default)
			)
			(layer "F.Fab")
		)
		(fp_line
			(start 0.299974 -0.150114)
			(end 0.299974 0.150114)
			(stroke
				(width 0.1)
				(type default)
			)
			(layer "F.Fab")
		)
		(fp_line
			(start 0.299974 0.150114)
			(end -0.299974 0.150114)
			(stroke
				(width 0.1)
				(type default)
			)
			(layer "F.Fab")
		)
		(pad "1" smd rect
			(at -0.2667 0)
			(size 0.3048 0.381)
			(layers "F.Cu" "F.Mask" "F.Paste")
			(net "P5E_PEX0_STN1_TX_DP<24>")
		)
		(pad "2" smd rect
			(at 0.2667 0)
			(size 0.3048 0.381)
			(layers "F.Cu" "F.Mask" "F.Paste")
			(net "P5E_PEX0_STN1_TX_C_DP<24>")
		)
	)
	(footprint ""
		(layer "F.Cu")
		(at 82.661506 -144.396714 180)
		(property "Reference" "C14"
			(at 0 0 180)
			(layer "F.SilkS")
			(hide yes)
			(effects
				(font
					(size 1.27 1.27)
				)
			)
		)
		(property "Value" ""
			(at 0 0 180)
			(layer "F.Fab")
			(effects
				(font
					(size 1.27 1.27)
				)
			)
		)
		(duplicate_pad_numbers_are_jumpers no)
		(fp_line
			(start 0.299974 0.150114)
			(end -0.299974 0.150114)
			(stroke
				(width 0.1)
				(type default)
			)
			(layer "F.Fab")
		)
		(fp_line
			(start 0.299974 -0.150114)
			(end 0.299974 0.150114)
			(stroke
				(width 0.1)
				(type default)
			)
			(layer "F.Fab")
		)
		(fp_line
			(start -0.299974 0.150114)
			(end -0.299974 -0.150114)
			(stroke
				(width 0.1)
				(type default)
			)
			(layer "F.Fab")
		)
		(fp_line
			(start -0.299974 -0.150114)
			(end 0.299974 -0.150114)
			(stroke
				(width 0.1)
				(type default)
			)
			(layer "F.Fab")
		)
		(pad "1" smd rect
			(at -0.2667 0 180)
			(size 0.3048 0.381)
			(layers "F.Cu" "F.Mask" "F.Paste")
			(net "P5E_PEX0_STN0_TX_DN<9>")
		)
		(pad "2" smd rect
			(at 0.2667 0 180)
			(size 0.3048 0.381)
			(layers "F.Cu" "F.Mask" "F.Paste")
			(net "P5E_PEX0_STN0_TX_C_DN<9>")
		)
	)
	(footprint ""
		(layer "F.Cu")
		(at 136.675622 -69.47916 180)
		(property "Reference" "PU107"
			(at -1.908048 4.07924 90)
			(unlocked yes)
			(layer "F.SilkS")
			(effects
				(font
					(size 0.7874 0.5842)
					(thickness 0.1524)
				)
			)
		)
		(property "Value" ""
			(at 0 0 180)
			(layer "F.Fab")
			(effects
				(font
					(size 1.27 1.27)
				)
			)
		)
		(duplicate_pad_numbers_are_jumpers no)
		(fp_line
			(start 1.239774 1.495298)
			(end -1.239774 1.495298)
			(stroke
				(width 0.1524)
				(type default)
			)
			(layer "F.SilkS")
		)
		(fp_line
			(start 1.239774 -1.495298)
			(end 1.239774 1.495298)
			(stroke
				(width 0.1524)
				(type default)
			)
			(layer "F.SilkS")
		)
		(fp_line
			(start -1.239774 1.495298)
			(end -1.239774 -1.495298)
			(stroke
				(width 0.1524)
				(type default)
			)
			(layer "F.SilkS")
		)
		(fp_line
			(start -1.239774 -1.495298)
			(end 1.239774 -1.495298)
			(stroke
				(width 0.1524)
				(type default)
			)
			(layer "F.SilkS")
		)
		(fp_poly
			(pts
				(xy -1.562608 -0.953516) (xy -2.28092 -0.235204) (xy -1.203452 0.124206)
			)
			(stroke
				(width 0)
				(type default)
			)
			(fill yes)
			(layer "F.SilkS")
		)
		(fp_line
			(start 0.8001 1.050036)
			(end -0.8001 1.050036)
			(stroke
				(width 0.1)
				(type default)
			)
			(layer "F.Fab")
		)
		(fp_line
			(start 0.8001 -1.050036)
			(end 0.8001 1.050036)
			(stroke
				(width 0.1)
				(type default)
			)
			(layer "F.Fab")
		)
		(fp_line
			(start -0.8001 1.050036)
			(end -0.8001 -1.050036)
			(stroke
				(width 0.1)
				(type default)
			)
			(layer "F.Fab")
		)
		(fp_line
			(start -0.8001 -1.050036)
			(end 0.8001 -1.050036)
			(stroke
				(width 0.1)
				(type default)
			)
			(layer "F.Fab")
		)
		(fp_poly
			(pts
				(xy -2.458974 -0.508) (xy -2.458974 0.508) (xy -1.442974 0)
			)
			(stroke
				(width 0)
				(type default)
			)
			(fill yes)
			(layer "F.Fab")
		)
		(pad "1_2" smd circle
			(at -0.374904 0 270)
			(size 0 0)
			(layers "F.Cu" "F.Mask" "F.Paste")
			(net "P12V_AUX")
		)
		(pad "3" smd rect
			(at -0.499872 0.999998 180)
			(size 0.254 0.7112)
			(layers "F.Cu" "F.Mask" "F.Paste")
			(net "GND")
		)
		(pad "4" smd rect
			(at 0 0.999998 180)
			(size 0.254 0.7112)
			(layers "F.Cu" "F.Mask" "F.Paste")
			(net "P12V_SSD4_CO_ILIMIT")
		)
		(pad "5" smd rect
			(at 0.499872 0.999998 180)
			(size 0.254 0.7112)
			(layers "F.Cu" "F.Mask" "F.Paste")
			(net "P12V_SSD4_CO_MODE")
		)
		(pad "6_7" smd circle
			(at 0.374904 0 90)
			(size 0 0)
			(layers "F.Cu" "F.Mask" "F.Paste")
			(net "P12V_SSD4_R")
		)
		(pad "8" smd rect
			(at 0.499872 -0.999998 180)
			(size 0.254 0.7112)
			(layers "F.Cu" "F.Mask" "F.Paste")
			(net "P12V_SSD4_CO_GATE")
		)
		(pad "9" smd rect
			(at 0 -0.999998 180)
			(size 0.254 0.7112)
			(layers "F.Cu" "F.Mask" "F.Paste")
			(net "P12V_SSD4_CO_EN")
		)
		(pad "10" smd rect
			(at -0.499872 -0.999998 180)
			(size 0.254 0.7112)
			(layers "F.Cu" "F.Mask" "F.Paste")
			(net "P12V_SSD4_CO_DV_DT")
		)
	)
	(footprint ""
		(layer "F.Cu")
		(at 328.440034 -253.907036)
		(property "Reference" "J56"
			(at -1.4224 -4.562348 0)
			(unlocked yes)
			(layer "F.SilkS")
			(effects
				(font
					(size 0.7874 0.5842)
					(thickness 0.1524)
				)
				(justify left)
			)
		)
		(property "Value" ""
			(at 0 0 0)
			(layer "F.Fab")
			(effects
				(font
					(size 1.27 1.27)
				)
			)
		)
		(duplicate_pad_numbers_are_jumpers no)
		(fp_line
			(start -1.27 -3.81)
			(end 1.27 -3.81)
			(stroke
				(width 0.1524)
				(type default)
			)
			(layer "F.SilkS")
		)
		(fp_line
			(start -1.27 -0.7747)
			(end -1.27 -3.81)
			(stroke
				(width 0.1524)
				(type default)
			)
			(layer "F.SilkS")
		)
		(fp_line
			(start -1.27 3.81)
			(end -1.27 0.7747)
			(stroke
				(width 0.1524)
				(type default)
			)
			(layer "F.SilkS")
		)
		(fp_line
			(start 1.27 -3.81)
			(end 1.27 -3.3147)
			(stroke
				(width 0.1524)
				(type default)
			)
			(layer "F.SilkS")
		)
		(fp_line
			(start 1.27 -1.7653)
			(end 1.27 1.7653)
			(stroke
				(width 0.1524)
				(type default)
			)
			(layer "F.SilkS")
		)
		(fp_line
			(start 1.27 3.3147)
			(end 1.27 3.81)
			(stroke
				(width 0.1524)
				(type default)
			)
			(layer "F.SilkS")
		)
		(fp_line
			(start 1.27 3.81)
			(end -1.27 3.81)
			(stroke
				(width 0.1524)
				(type default)
			)
			(layer "F.SilkS")
		)
		(fp_poly
			(pts
				(xy 4.3942 -3.048) (xy 4.3942 -2.032) (xy 3.3782 -2.54)
			)
			(stroke
				(width 0)
				(type default)
			)
			(fill yes)
			(layer "F.SilkS")
		)
		(fp_line
			(start -1.27 -3.81)
			(end -1.27 3.81)
			(stroke
				(width 0.1)
				(type default)
			)
			(layer "F.Fab")
		)
		(fp_line
			(start -1.27 3.81)
			(end 1.27 3.81)
			(stroke
				(width 0.1)
				(type default)
			)
			(layer "F.Fab")
		)
		(fp_line
			(start 1.27 -3.81)
			(end -1.27 -3.81)
			(stroke
				(width 0.1)
				(type default)
			)
			(layer "F.Fab")
		)
		(fp_line
			(start 1.27 3.81)
			(end 1.27 -3.81)
			(stroke
				(width 0.1)
				(type default)
			)
			(layer "F.Fab")
		)
		(fp_poly
			(pts
				(xy 4.3942 -3.048) (xy 4.3942 -2.032) (xy 3.3782 -2.54)
			)
			(stroke
				(width 0)
				(type default)
			)
			(fill yes)
			(layer "F.Fab")
		)
		(fp_text user "3"
			(at 4.430014 2.728468 90)
			(unlocked yes)
			(layer "F.SilkS")
			(effects
				(font
					(size 0.7874 0.5842)
					(thickness 0.1524)
				)
			)
		)
		(fp_text user "3"
			(at 3.921252 2.54 90)
			(unlocked yes)
			(layer "F.Fab")
			(effects
				(font
					(size 0.7874 0.5842)
					(thickness 0.1524)
				)
			)
		)
		(pad "1" smd rect
			(at 1.459992 -2.54 90)
			(size 1.27 3.429)
			(layers "F.Cu" "F.Mask" "F.Paste")
			(net "Net_2677")
		)
		(pad "2" smd rect
			(at -1.459992 0 90)
			(size 1.27 3.429)
			(layers "F.Cu" "F.Mask" "F.Paste")
			(net "JP_FPGA_FRC_PWRON_N")
		)
		(pad "3" smd rect
			(at 1.459992 2.54 90)
			(size 1.27 3.429)
			(layers "F.Cu" "F.Mask" "F.Paste")
			(net "GND")
		)
	)
	(footprint ""
		(layer "F.Cu")
		(at 27.386788 -307.803296 -135)
		(property "Reference" "R1086"
			(at 0 0 225)
			(layer "F.SilkS")
			(hide yes)
			(effects
				(font
					(size 1.27 1.27)
				)
			)
		)
		(property "Value" ""
			(at 0 0 225)
			(layer "F.Fab")
			(effects
				(font
					(size 1.27 1.27)
				)
			)
		)
		(duplicate_pad_numbers_are_jumpers no)
		(fp_line
			(start 0.787389 0.406267)
			(end -0.787389 0.406267)
			(stroke
				(width 0.1524)
				(type default)
			)
			(layer "F.SilkS")
		)
		(fp_line
			(start 0.787389 -0.406267)
			(end 0.787389 0.406267)
			(stroke
				(width 0.1524)
				(type default)
			)
			(layer "F.SilkS")
		)
		(fp_line
			(start -0.787389 0.406267)
			(end -0.787389 -0.406267)
			(stroke
				(width 0.1524)
				(type default)
			)
			(layer "F.SilkS")
		)
		(fp_line
			(start -0.787389 -0.406267)
			(end 0.787389 -0.406267)
			(stroke
				(width 0.1524)
				(type default)
			)
			(layer "F.SilkS")
		)
		(fp_line
			(start 0.679446 0.30479)
			(end 0.120515 0.30479)
			(stroke
				(width 0.1)
				(type default)
			)
			(layer "F.Fab")
		)
		(fp_line
			(start 0.120515 0.30479)
			(end 0.120335 0.279466)
			(stroke
				(width 0.1)
				(type default)
			)
			(layer "F.Fab")
		)
		(fp_line
			(start 0.120335 0.279466)
			(end -0.120695 0.279466)
			(stroke
				(width 0.1)
				(type default)
			)
			(layer "F.Fab")
		)
		(fp_line
			(start 0.679446 -0.30479)
			(end 0.679446 0.30479)
			(stroke
				(width 0.1)
				(type default)
			)
			(layer "F.Fab")
		)
		(fp_line
			(start -0.120515 0.30479)
			(end -0.679446 0.30479)
			(stroke
				(width 0.1)
				(type default)
			)
			(layer "F.Fab")
		)
		(fp_line
			(start -0.120695 0.279466)
			(end -0.120515 0.30479)
			(stroke
				(width 0.1)
				(type default)
			)
			(layer "F.Fab")
		)
		(fp_line
			(start 0.120695 -0.279466)
			(end 0.120515 -0.30479)
			(stroke
				(width 0.1)
				(type default)
			)
			(layer "F.Fab")
		)
		(fp_line
			(start 0.120515 -0.30479)
			(end 0.679446 -0.30479)
			(stroke
				(width 0.1)
				(type default)
			)
			(layer "F.Fab")
		)
		(fp_line
			(start -0.679446 0.30479)
			(end -0.679446 -0.305149)
			(stroke
				(width 0.1)
				(type default)
			)
			(layer "F.Fab")
		)
		(fp_line
			(start -0.120695 -0.279466)
			(end 0.120695 -0.279466)
			(stroke
				(width 0.1)
				(type default)
			)
			(layer "F.Fab")
		)
		(fp_line
			(start -0.120695 -0.304969)
			(end -0.120695 -0.279466)
			(stroke
				(width 0.1)
				(type default)
			)
			(layer "F.Fab")
		)
		(fp_line
			(start -0.679446 -0.305149)
			(end -0.120695 -0.304969)
			(stroke
				(width 0.1)
				(type default)
			)
			(layer "F.Fab")
		)
		(pad "1" smd circle
			(at -0.40005 0 225)
			(size 0 0)
			(layers "F.Cu" "F.Mask" "F.Paste")
			(net "PEX0_DBG_SEL0")
		)
		(pad "2" smd circle
			(at 0.40005 0 225)
			(size 0 0)
			(layers "F.Cu" "F.Mask" "F.Paste")
			(net "P1V8_PEX")
		)
	)
)
